(kicad_pcb
	(version 20260206)
	(generator "pcbnew")
	(generator_version "10.0")
	(general
		(thickness 1.6)
		(legacy_teardrops no)
	)
	(paper "A4")
	(title_block
		(title "v1-chassis-manager — T6M_CM_d_v01_1031_1645.brd")
		(comment 1 "Open CloudServer (Microsoft) / footprints 2374-2383 of 2512")
	)
	(layers
		(0 "F.Cu" signal "TOP")
		(4 "In1.Cu" signal "GND1")
		(6 "In2.Cu" signal "IN1")
		(8 "In3.Cu" signal "VCC1")
		(10 "In4.Cu" signal "VCC2")
		(12 "In5.Cu" signal "GND2")
		(14 "In6.Cu" signal "IN2")
		(16 "In7.Cu" signal "IN3")
		(18 "In8.Cu" signal "GND3")
		(2 "B.Cu" signal "BOTTOM")
		(9 "F.Adhes" user "F.Adhesive")
		(11 "B.Adhes" user "B.Adhesive")
		(13 "F.Paste" user "Package Geometry/Pastemask Top")
		(15 "B.Paste" user "Package Geometry/Pastemask Bottom")
		(5 "F.SilkS" user "Ref Des/Silkscreen Top")
		(7 "B.SilkS" user "Ref Des/Silkscreen Bottom")
		(1 "F.Mask" user "Board Geometry/Soldermask Top")
		(3 "B.Mask" user "Board Geometry/Soldermask Bottom")
		(17 "Dwgs.User" user "User.Drawings")
		(19 "Cmts.User" user "User.Comments")
		(21 "Eco1.User" user "User.Eco1")
		(23 "Eco2.User" user "User.Eco2")
		(25 "Edge.Cuts" user "Board Geometry/Outline")
		(27 "Margin" user)
		(31 "F.CrtYd" user "Package Geometry/Place Bound Top")
		(29 "B.CrtYd" user "Package Geometry/Place Bound Bottom")
		(35 "F.Fab" user "Ref Des/Assembly Top")
		(33 "B.Fab" user "Ref Des/Assembly Bottom")
	)
	(footprint ""
		(layer "B.Cu")
		(at 58.087006 -125.121924 90)
		(property "Reference" "C269"
			(at -54.315868 -40.971724 270)
			(unlocked yes)
			(layer "B.SilkS")
			(effects
				(font
					(size 0.7874 0.5842)
					(thickness 0.1524)
				)
				(justify left mirror)
			)
		)
		(property "Value" ""
			(at 0 0 90)
			(layer "B.Fab")
			(effects
				(font
					(size 1.27 1.27)
				)
				(justify mirror)
			)
		)
		(duplicate_pad_numbers_are_jumpers no)
		(fp_line
			(start 0.7874 -0.4064)
			(end -0.7874 -0.4064)
			(stroke
				(width 0.1524)
				(type default)
			)
			(layer "B.SilkS")
		)
		(fp_line
			(start -0.7874 -0.4064)
			(end -0.7874 0.4064)
			(stroke
				(width 0.1524)
				(type default)
			)
			(layer "B.SilkS")
		)
		(fp_line
			(start 0 0.381)
			(end 0 -0.381)
			(stroke
				(width 0.1524)
				(type default)
			)
			(layer "B.SilkS")
		)
		(fp_line
			(start 0.7874 0.4064)
			(end 0.7874 -0.4064)
			(stroke
				(width 0.1524)
				(type default)
			)
			(layer "B.SilkS")
		)
		(fp_line
			(start -0.7874 0.4064)
			(end 0.7874 0.4064)
			(stroke
				(width 0.1524)
				(type default)
			)
			(layer "B.SilkS")
		)
		(fp_poly
			(pts
				(xy 0.5334 0.254) (xy 0.635 0.254) (xy 0.635 0.2286) (xy 0.635 -0.254) (xy 0.5334 -0.254) (xy 0.5334 -0.2794)
				(xy -0.5334 -0.2794) (xy -0.5334 -0.254) (xy -0.635 -0.254) (xy -0.635 0.254) (xy -0.5334 0.254)
				(xy -0.5334 0.2794) (xy 0.508 0.2794) (xy 0.5334 0.2794)
			)
			(stroke
				(width 0)
				(type default)
			)
			(fill no)
			(layer "B.CrtYd")
		)
		(pad "1" smd rect
			(at -0.40005 0 270)
			(size 0.4572 0.508)
			(layers "B.Cu" "B.Mask" "B.Paste")
			(net "BMC_NODE1_HPLLAV33")
		)
		(pad "2" smd rect
			(at 0.40005 0 270)
			(size 0.4572 0.508)
			(layers "B.Cu" "B.Mask" "B.Paste")
			(net "GND")
		)
	)
	(footprint ""
		(layer "B.Cu")
		(at 165.252908 -185.083196 180)
		(property "Reference" "R1308"
			(at -6.483604 7.920482 0)
			(unlocked yes)
			(layer "B.SilkS")
			(effects
				(font
					(size 0.7874 0.5842)
					(thickness 0.1524)
				)
				(justify left mirror)
			)
		)
		(property "Value" ""
			(at 0 0 0)
			(layer "B.Fab")
			(effects
				(font
					(size 1.27 1.27)
				)
				(justify mirror)
			)
		)
		(duplicate_pad_numbers_are_jumpers no)
		(fp_line
			(start 0.7874 0.4064)
			(end 0.7874 -0.4064)
			(stroke
				(width 0.1524)
				(type default)
			)
			(layer "B.SilkS")
		)
		(fp_line
			(start 0.7874 -0.4064)
			(end -0.7874 -0.4064)
			(stroke
				(width 0.1524)
				(type default)
			)
			(layer "B.SilkS")
		)
		(fp_line
			(start -0.7874 0.4064)
			(end 0.7874 0.4064)
			(stroke
				(width 0.1524)
				(type default)
			)
			(layer "B.SilkS")
		)
		(fp_line
			(start -0.7874 -0.4064)
			(end -0.7874 0.4064)
			(stroke
				(width 0.1524)
				(type default)
			)
			(layer "B.SilkS")
		)
		(fp_poly
			(pts
				(xy 0.508 0.2794) (xy 0.508 0.2286) (xy 0.635 0.2286) (xy 0.635 -0.254) (xy 0.5334 -0.254) (xy 0.5334 -0.2794)
				(xy -0.5334 -0.2794) (xy -0.5334 -0.254) (xy -0.635 -0.254) (xy -0.635 0.254) (xy -0.5334 0.254)
				(xy -0.5334 0.2794)
			)
			(stroke
				(width 0)
				(type default)
			)
			(fill no)
			(layer "B.CrtYd")
		)
		(pad "1" smd rect
			(at -0.40005 0)
			(size 0.4572 0.508)
			(layers "B.Cu" "B.Mask" "B.Paste")
			(net "P3V3_NODE1")
		)
		(pad "2" smd rect
			(at 0.40005 0)
			(size 0.4572 0.508)
			(layers "B.Cu" "B.Mask" "B.Paste")
			(net "N54365772")
		)
	)
	(footprint ""
		(layer "B.Cu")
		(at 110.44936 -177.585624 180)
		(property "Reference" "R713"
			(at 21.356828 -32.269176 0)
			(unlocked yes)
			(layer "B.SilkS")
			(effects
				(font
					(size 0.7874 0.5842)
					(thickness 0.1524)
				)
				(justify left mirror)
			)
		)
		(property "Value" ""
			(at 0 0 0)
			(layer "B.Fab")
			(effects
				(font
					(size 1.27 1.27)
				)
				(justify mirror)
			)
		)
		(duplicate_pad_numbers_are_jumpers no)
		(fp_line
			(start 0.7874 0.4064)
			(end 0.7874 -0.4064)
			(stroke
				(width 0.1524)
				(type default)
			)
			(layer "B.SilkS")
		)
		(fp_line
			(start 0.7874 -0.4064)
			(end -0.7874 -0.4064)
			(stroke
				(width 0.1524)
				(type default)
			)
			(layer "B.SilkS")
		)
		(fp_line
			(start -0.7874 0.4064)
			(end 0.7874 0.4064)
			(stroke
				(width 0.1524)
				(type default)
			)
			(layer "B.SilkS")
		)
		(fp_line
			(start -0.7874 -0.4064)
			(end -0.7874 0.4064)
			(stroke
				(width 0.1524)
				(type default)
			)
			(layer "B.SilkS")
		)
		(fp_poly
			(pts
				(xy 0.508 0.2794) (xy 0.508 0.2286) (xy 0.635 0.2286) (xy 0.635 -0.254) (xy 0.5334 -0.254) (xy 0.5334 -0.2794)
				(xy -0.5334 -0.2794) (xy -0.5334 -0.254) (xy -0.635 -0.254) (xy -0.635 0.254) (xy -0.5334 0.254)
				(xy -0.5334 0.2794)
			)
			(stroke
				(width 0)
				(type default)
			)
			(fill no)
			(layer "B.CrtYd")
		)
		(pad "1" smd rect
			(at -0.40005 0)
			(size 0.4572 0.508)
			(layers "B.Cu" "B.Mask" "B.Paste")
			(net "T5_NODE4_EN")
		)
		(pad "2" smd rect
			(at 0.40005 0)
			(size 0.4572 0.508)
			(layers "B.Cu" "B.Mask" "B.Paste")
			(net "P5V_NODE1")
		)
	)
	(footprint ""
		(layer "B.Cu")
		(at 157.33776 -187.872624 -90)
		(property "Reference" "C597"
			(at -4.565396 3.861308 270)
			(unlocked yes)
			(layer "B.SilkS")
			(effects
				(font
					(size 0.7874 0.5842)
					(thickness 0.1524)
				)
				(justify left mirror)
			)
		)
		(property "Value" ""
			(at 0 0 90)
			(layer "B.Fab")
			(effects
				(font
					(size 1.27 1.27)
				)
				(justify mirror)
			)
		)
		(duplicate_pad_numbers_are_jumpers no)
		(fp_line
			(start -0.7874 0.4064)
			(end 0.7874 0.4064)
			(stroke
				(width 0.1524)
				(type default)
			)
			(layer "B.SilkS")
		)
		(fp_line
			(start 0.7874 0.4064)
			(end 0.7874 -0.4064)
			(stroke
				(width 0.1524)
				(type default)
			)
			(layer "B.SilkS")
		)
		(fp_line
			(start 0 0.381)
			(end 0 -0.381)
			(stroke
				(width 0.1524)
				(type default)
			)
			(layer "B.SilkS")
		)
		(fp_line
			(start -0.7874 -0.4064)
			(end -0.7874 0.4064)
			(stroke
				(width 0.1524)
				(type default)
			)
			(layer "B.SilkS")
		)
		(fp_line
			(start 0.7874 -0.4064)
			(end -0.7874 -0.4064)
			(stroke
				(width 0.1524)
				(type default)
			)
			(layer "B.SilkS")
		)
		(fp_poly
			(pts
				(xy 0.5334 0.254) (xy 0.635 0.254) (xy 0.635 0.2286) (xy 0.635 -0.254) (xy 0.5334 -0.254) (xy 0.5334 -0.2794)
				(xy -0.5334 -0.2794) (xy -0.5334 -0.254) (xy -0.635 -0.254) (xy -0.635 0.254) (xy -0.5334 0.254)
				(xy -0.5334 0.2794) (xy 0.508 0.2794) (xy 0.5334 0.2794)
			)
			(stroke
				(width 0)
				(type default)
			)
			(fill no)
			(layer "B.CrtYd")
		)
		(pad "1" smd rect
			(at -0.40005 0 90)
			(size 0.4572 0.508)
			(layers "B.Cu" "B.Mask" "B.Paste")
			(net "I2C_PSU3_R_SCL")
		)
		(pad "2" smd rect
			(at 0.40005 0 90)
			(size 0.4572 0.508)
			(layers "B.Cu" "B.Mask" "B.Paste")
			(net "GND")
		)
	)
	(footprint ""
		(layer "B.Cu")
		(at 156.19476 -184.951624 90)
		(property "Reference" "R826"
			(at 4.230624 -1.838198 270)
			(unlocked yes)
			(layer "B.SilkS")
			(effects
				(font
					(size 0.7874 0.5842)
					(thickness 0.1524)
				)
				(justify left mirror)
			)
		)
		(property "Value" ""
			(at 0 0 90)
			(layer "B.Fab")
			(effects
				(font
					(size 1.27 1.27)
				)
				(justify mirror)
			)
		)
		(duplicate_pad_numbers_are_jumpers no)
		(fp_line
			(start 0.7874 -0.4064)
			(end -0.7874 -0.4064)
			(stroke
				(width 0.1524)
				(type default)
			)
			(layer "B.SilkS")
		)
		(fp_line
			(start -0.7874 -0.4064)
			(end -0.7874 0.4064)
			(stroke
				(width 0.1524)
				(type default)
			)
			(layer "B.SilkS")
		)
		(fp_line
			(start 0.7874 0.4064)
			(end 0.7874 -0.4064)
			(stroke
				(width 0.1524)
				(type default)
			)
			(layer "B.SilkS")
		)
		(fp_line
			(start -0.7874 0.4064)
			(end 0.7874 0.4064)
			(stroke
				(width 0.1524)
				(type default)
			)
			(layer "B.SilkS")
		)
		(fp_poly
			(pts
				(xy 0.508 0.2794) (xy 0.508 0.2286) (xy 0.635 0.2286) (xy 0.635 -0.254) (xy 0.5334 -0.254) (xy 0.5334 -0.2794)
				(xy -0.5334 -0.2794) (xy -0.5334 -0.254) (xy -0.635 -0.254) (xy -0.635 0.254) (xy -0.5334 0.254)
				(xy -0.5334 0.2794)
			)
			(stroke
				(width 0)
				(type default)
			)
			(fill no)
			(layer "B.CrtYd")
		)
		(pad "1" smd rect
			(at -0.40005 0 270)
			(size 0.4572 0.508)
			(layers "B.Cu" "B.Mask" "B.Paste")
			(net "I2C_PSU3_SDA")
		)
		(pad "2" smd rect
			(at 0.40005 0 270)
			(size 0.4572 0.508)
			(layers "B.Cu" "B.Mask" "B.Paste")
			(net "I2C_PSU3_R_SDA")
		)
	)
	(footprint ""
		(layer "B.Cu")
		(at 58.602372 -71.370698)
		(property "Reference" "PJ8"
			(at -13.960602 34.763456 270)
			(unlocked yes)
			(layer "B.SilkS")
			(effects
				(font
					(size 0.7874 0.5842)
					(thickness 0.1524)
				)
				(justify left mirror)
			)
		)
		(property "Value" ""
			(at 0 0 0)
			(layer "B.Fab")
			(effects
				(font
					(size 1.27 1.27)
				)
				(justify mirror)
			)
		)
		(duplicate_pad_numbers_are_jumpers no)
		(fp_poly
			(pts
				(xy -0.2794 0.907796) (xy -0.254 0.907796) (xy -0.254 1.0414) (xy 0.254 1.0414) (xy 0.254 1.034796)
				(xy 0.254 0.933196) (xy 0.2794 0.933196) (xy 0.2794 -0.133604) (xy 0.254 -0.133604) (xy 0.254 -0.235204)
				(xy -0.254 -0.235204) (xy -0.254 -0.133604) (xy -0.2794 -0.133604)
			)
			(stroke
				(width 0)
				(type default)
			)
			(fill no)
			(layer "B.CrtYd")
		)
		(pad "1" smd custom
			(at 0 -0.000254 180)
			(size 0.127 0.127)
			(layers "B.Cu" "B.Mask" "B.Paste")
			(net "P1V05_NODE1")
			(options
				(clearance outline)
				(anchor circle)
			)
			(primitives
				(gr_poly
					(pts
						(xy -0.127 -0.508) (xy -0.127 0.0508) (xy -0.254 0.0508) (xy -0.254 0.508) (xy 0.254 0.508) (xy 0.254 0.0508)
						(xy 0.127 0.0508) (xy 0.127 -0.508)
					)
					(width 0)
					(fill yes)
				)
			)
		)
		(pad "2" smd rect
			(at 0 0.799846 90)
			(size 0.4572 0.508)
			(layers "B.Cu" "B.Mask" "B.Paste")
			(net "VSENSE_P1V05_NODE1_P")
		)
		(zone
			(layer "B.Cu")
			(hatch none 0.5)
			(connect_pads
				(clearance 0)
			)
			(min_thickness 0.25)
			(keepout
				(tracks allowed)
				(vias not_allowed)
				(pads allowed)
				(copperpour not_allowed)
				(footprints allowed)
			)
			(placement
				(enabled no)
				(sheetname "")
			)
			(fill
				(thermal_gap 0.5)
				(thermal_bridge_width 0.5)
				(island_removal_mode 0)
			)
			(polygon
				(pts
					(xy 58.907172 -70.285102) (xy 58.297572 -70.285102) (xy 58.297572 -71.656702) (xy 58.907172 -71.656702)
				)
			)
		)
	)
	(footprint ""
		(layer "B.Cu")
		(at 103.329994 -116.985796)
		(property "Reference" "PC124"
			(at -2.577846 0.009144 0)
			(unlocked yes)
			(layer "B.SilkS")
			(effects
				(font
					(size 0.7874 0.5842)
					(thickness 0.1524)
				)
				(justify left mirror)
			)
		)
		(property "Value" ""
			(at 0 0 0)
			(layer "B.Fab")
			(effects
				(font
					(size 1.27 1.27)
				)
				(justify mirror)
			)
		)
		(duplicate_pad_numbers_are_jumpers no)
		(fp_line
			(start -1.905 -0.8636)
			(end -1.905 0.8636)
			(stroke
				(width 0.1524)
				(type default)
			)
			(layer "B.SilkS")
		)
		(fp_line
			(start -1.905 0.8636)
			(end 1.905 0.8636)
			(stroke
				(width 0.1524)
				(type default)
			)
			(layer "B.SilkS")
		)
		(fp_line
			(start 0 0.8382)
			(end 0 -0.8382)
			(stroke
				(width 0.1524)
				(type default)
			)
			(layer "B.SilkS")
		)
		(fp_line
			(start 1.905 -0.8636)
			(end -1.905 -0.8636)
			(stroke
				(width 0.1524)
				(type default)
			)
			(layer "B.SilkS")
		)
		(fp_line
			(start 1.905 0.8636)
			(end 1.905 -0.8636)
			(stroke
				(width 0.1524)
				(type default)
			)
			(layer "B.SilkS")
		)
		(fp_rect
			(start 1.524 0.7366)
			(end -1.524 -0.7366)
			(stroke
				(width 0)
				(type default)
			)
			(fill no)
			(layer "B.CrtYd")
		)
		(pad "1" smd rect
			(at -0.94996 0 180)
			(size 1.1176 1.3716)
			(layers "B.Cu" "B.Mask" "B.Paste")
			(net "GND")
		)
		(pad "2" smd rect
			(at 0.94996 0 180)
			(size 1.1176 1.3716)
			(layers "B.Cu" "B.Mask" "B.Paste")
			(net "PV_VCCP_NODE1")
		)
	)
	(footprint ""
		(layer "B.Cu")
		(at 106.28376 -185.205624 90)
		(property "Reference" "R896"
			(at 3.957828 0.394208 270)
			(unlocked yes)
			(layer "B.SilkS")
			(effects
				(font
					(size 0.7874 0.5842)
					(thickness 0.1524)
				)
				(justify left mirror)
			)
		)
		(property "Value" ""
			(at 0 0 90)
			(layer "B.Fab")
			(effects
				(font
					(size 1.27 1.27)
				)
				(justify mirror)
			)
		)
		(duplicate_pad_numbers_are_jumpers no)
		(fp_line
			(start 0.7874 -0.4064)
			(end -0.7874 -0.4064)
			(stroke
				(width 0.1524)
				(type default)
			)
			(layer "B.SilkS")
		)
		(fp_line
			(start -0.7874 -0.4064)
			(end -0.7874 0.4064)
			(stroke
				(width 0.1524)
				(type default)
			)
			(layer "B.SilkS")
		)
		(fp_line
			(start 0.7874 0.4064)
			(end 0.7874 -0.4064)
			(stroke
				(width 0.1524)
				(type default)
			)
			(layer "B.SilkS")
		)
		(fp_line
			(start -0.7874 0.4064)
			(end 0.7874 0.4064)
			(stroke
				(width 0.1524)
				(type default)
			)
			(layer "B.SilkS")
		)
		(fp_poly
			(pts
				(xy 0.508 0.2794) (xy 0.508 0.2286) (xy 0.635 0.2286) (xy 0.635 -0.254) (xy 0.5334 -0.254) (xy 0.5334 -0.2794)
				(xy -0.5334 -0.2794) (xy -0.5334 -0.254) (xy -0.635 -0.254) (xy -0.635 0.254) (xy -0.5334 0.254)
				(xy -0.5334 0.2794)
			)
			(stroke
				(width 0)
				(type default)
			)
			(fill no)
			(layer "B.CrtYd")
		)
		(pad "1" smd rect
			(at -0.40005 0 270)
			(size 0.4572 0.508)
			(layers "B.Cu" "B.Mask" "B.Paste")
			(net "T5_NODE1_EN")
		)
		(pad "2" smd rect
			(at 0.40005 0 270)
			(size 0.4572 0.508)
			(layers "B.Cu" "B.Mask" "B.Paste")
			(net "T5_NODE1_EN_R")
		)
	)
	(footprint ""
		(layer "B.Cu")
		(at 68.353686 -121.044462 90)
		(property "Reference" "R330"
			(at -7.37235 9.927336 270)
			(unlocked yes)
			(layer "B.SilkS")
			(effects
				(font
					(size 0.7874 0.5842)
					(thickness 0.1524)
				)
				(justify left mirror)
			)
		)
		(property "Value" ""
			(at 0 0 90)
			(layer "B.Fab")
			(effects
				(font
					(size 1.27 1.27)
				)
				(justify mirror)
			)
		)
		(duplicate_pad_numbers_are_jumpers no)
		(fp_line
			(start 0.7874 -0.4064)
			(end -0.7874 -0.4064)
			(stroke
				(width 0.1524)
				(type default)
			)
			(layer "B.SilkS")
		)
		(fp_line
			(start -0.7874 -0.4064)
			(end -0.7874 0.4064)
			(stroke
				(width 0.1524)
				(type default)
			)
			(layer "B.SilkS")
		)
		(fp_line
			(start 0.7874 0.4064)
			(end 0.7874 -0.4064)
			(stroke
				(width 0.1524)
				(type default)
			)
			(layer "B.SilkS")
		)
		(fp_line
			(start -0.7874 0.4064)
			(end 0.7874 0.4064)
			(stroke
				(width 0.1524)
				(type default)
			)
			(layer "B.SilkS")
		)
		(fp_poly
			(pts
				(xy 0.508 0.2794) (xy 0.508 0.2286) (xy 0.635 0.2286) (xy 0.635 -0.254) (xy 0.5334 -0.254) (xy 0.5334 -0.2794)
				(xy -0.5334 -0.2794) (xy -0.5334 -0.254) (xy -0.635 -0.254) (xy -0.635 0.254) (xy -0.5334 0.254)
				(xy -0.5334 0.2794)
			)
			(stroke
				(width 0)
				(type default)
			)
			(fill no)
			(layer "B.CrtYd")
		)
		(pad "1" smd rect
			(at -0.40005 0 270)
			(size 0.4572 0.508)
			(layers "B.Cu" "B.Mask" "B.Paste")
			(net "P3V3_NODE1")
		)
		(pad "2" smd rect
			(at 0.40005 0 270)
			(size 0.4572 0.508)
			(layers "B.Cu" "B.Mask" "B.Paste")
			(net "BMC_ROMA14")
		)
	)
	(footprint ""
		(layer "B.Cu")
		(at 144.909032 -36.678616)
		(property "Reference" "R1078"
			(at 1.24714 17.425924 0)
			(unlocked yes)
			(layer "B.SilkS")
			(effects
				(font
					(size 0.7874 0.5842)
					(thickness 0.1524)
				)
				(justify left mirror)
			)
		)
		(property "Value" ""
			(at 0 0 0)
			(layer "B.Fab")
			(effects
				(font
					(size 1.27 1.27)
				)
				(justify mirror)
			)
		)
		(duplicate_pad_numbers_are_jumpers no)
		(fp_line
			(start -0.7874 -0.4064)
			(end -0.7874 0.4064)
			(stroke
				(width 0.1524)
				(type default)
			)
			(layer "B.SilkS")
		)
		(fp_line
			(start -0.7874 0.4064)
			(end 0.7874 0.4064)
			(stroke
				(width 0.1524)
				(type default)
			)
			(layer "B.SilkS")
		)
		(fp_line
			(start 0.7874 -0.4064)
			(end -0.7874 -0.4064)
			(stroke
				(width 0.1524)
				(type default)
			)
			(layer "B.SilkS")
		)
		(fp_line
			(start 0.7874 0.4064)
			(end 0.7874 -0.4064)
			(stroke
				(width 0.1524)
				(type default)
			)
			(layer "B.SilkS")
		)
		(fp_poly
			(pts
				(xy 0.508 0.2794) (xy 0.508 0.2286) (xy 0.635 0.2286) (xy 0.635 -0.254) (xy 0.5334 -0.254) (xy 0.5334 -0.2794)
				(xy -0.5334 -0.2794) (xy -0.5334 -0.254) (xy -0.635 -0.254) (xy -0.635 0.254) (xy -0.5334 0.254)
				(xy -0.5334 0.2794)
			)
			(stroke
				(width 0)
				(type default)
			)
			(fill no)
			(layer "B.CrtYd")
		)
		(pad "1" smd rect
			(at -0.40005 0 180)
			(size 0.4572 0.508)
			(layers "B.Cu" "B.Mask" "B.Paste")
			(net "SIO_CPLD_RSV1_R")
		)
		(pad "2" smd rect
			(at 0.40005 0 180)
			(size 0.4572 0.508)
			(layers "B.Cu" "B.Mask" "B.Paste")
			(net "P3V3_NODE1")
		)
	)
)
